(kicad_pcb
	(version 20260206)
	(generator "pcbnew")
	(generator_version "10.0")
	(general
		(thickness 1.6)
		(legacy_teardrops no)
	)
	(paper "A4")
	(title_block
		(title "01162023_DA0F0TEBIF0_F0T_Expander_BD_F_brd_V02_OCP.brd")
		(comment 1 "Grand Teton / footprint 3770 of 9728 (J25), pads 1-109 of 179")
	)
	(layers
		(0 "F.Cu" signal "TOP")
		(4 "In1.Cu" signal "GND")
		(6 "In2.Cu" signal "VCC")
		(8 "In3.Cu" signal "VCC1")
		(10 "In4.Cu" signal "GND1")
		(12 "In5.Cu" signal "IN1")
		(14 "In6.Cu" signal "GND2")
		(16 "In7.Cu" signal "IN2")
		(18 "In8.Cu" signal "GND3")
		(20 "In9.Cu" signal "IN3")
		(22 "In10.Cu" signal "GND4")
		(24 "In11.Cu" signal "IN4")
		(26 "In12.Cu" signal "GND5")
		(28 "In13.Cu" signal "IN5")
		(30 "In14.Cu" signal "GND6")
		(32 "In15.Cu" signal "IN6")
		(34 "In16.Cu" signal "GND7")
		(2 "B.Cu" signal "BOTTOM")
		(9 "F.Adhes" user "F.Adhesive")
		(11 "B.Adhes" user "B.Adhesive")
		(13 "F.Paste" user "Package Geometry/Pastemask Top")
		(15 "B.Paste" user "Package Geometry/Pastemask Bottom")
		(5 "F.SilkS" user "Ref Des/Silkscreen Top")
		(7 "B.SilkS" user "Ref Des/Silkscreen Bottom")
		(1 "F.Mask" user "Board Geometry/Soldermask Top")
		(3 "B.Mask" user "Board Geometry/Soldermask Bottom")
		(17 "Dwgs.User" user "User.Drawings")
		(19 "Cmts.User" user "User.Comments")
		(21 "Eco1.User" user "User.Eco1")
		(23 "Eco2.User" user "User.Eco2")
		(25 "Edge.Cuts" user "Board Geometry/Outline")
		(27 "Margin" user)
		(31 "F.CrtYd" user "Package Geometry/Place Bound Top")
		(29 "B.CrtYd" user "Package Geometry/Place Bound Bottom")
		(35 "F.Fab" user "Ref Des/Assembly Top")
		(33 "B.Fab" user "Ref Des/Assembly Bottom")
	)
	(footprint ""
		(layer "F.Cu")
		(at 304.179986 -127.700024 180)
		(property "Reference" "J25"
			(at 5.322316 -34.482024 90)
			(unlocked yes)
			(layer "F.SilkS")
			(effects
				(font
					(size 0.7874 0.5842)
					(thickness 0.1524)
				)
				(justify left)
			)
		)
		(property "Value" ""
			(at 0 0 180)
			(layer "F.Fab")
			(effects
				(font
					(size 1.27 1.27)
				)
			)
		)
		(duplicate_pad_numbers_are_jumpers no)
		(pad "" np_thru_hole circle
			(at -0.727456 -32.485076 180)
			(size 1.1176 1.1176)
			(drill 1.1176)
			(layers "*.Cu" "*.Mask")
			(clearance 0.381)
			(thermal_gap 0.381)
		)
		(pad "" np_thru_hole circle
			(at 1.022604 32.485076 180)
			(size 1.1176 1.1176)
			(drill 1.1176)
			(layers "*.Cu" "*.Mask")
			(clearance 0.381)
			(thermal_gap 0.381)
		)
		(pad "A1" smd rect
			(at 3.322574 -18.465038 90)
			(size 0.3556 1.2192)
			(layers "F.Cu" "F.Mask" "F.Paste")
			(net "GND")
		)
		(pad "A2" smd rect
			(at 3.322574 -17.86509 90)
			(size 0.3556 1.2192)
			(layers "F.Cu" "F.Mask" "F.Paste")
			(net "GND")
		)
		(pad "A3" smd rect
			(at 3.322574 -17.264888 90)
			(size 0.3556 1.2192)
			(layers "F.Cu" "F.Mask" "F.Paste")
			(net "GND")
		)
		(pad "A4" smd rect
			(at 3.322574 -16.66494 90)
			(size 0.3556 1.2192)
			(layers "F.Cu" "F.Mask" "F.Paste")
			(net "GND")
		)
		(pad "A5" smd rect
			(at 3.322574 -16.064992 90)
			(size 0.3556 1.2192)
			(layers "F.Cu" "F.Mask" "F.Paste")
			(net "GND")
		)
		(pad "A6" smd rect
			(at 3.322574 -15.465044 90)
			(size 0.3556 1.2192)
			(layers "F.Cu" "F.Mask" "F.Paste")
			(net "GND")
		)
		(pad "A7" smd rect
			(at 3.322574 -14.865096 90)
			(size 0.3556 1.2192)
			(layers "F.Cu" "F.Mask" "F.Paste")
			(net "SMB_NIC5_LS_SCL")
		)
		(pad "A8" smd rect
			(at 3.322574 -14.264894 90)
			(size 0.3556 1.2192)
			(layers "F.Cu" "F.Mask" "F.Paste")
			(net "SMB_NIC5_LS_SDA")
		)
		(pad "A9" smd rect
			(at 3.322574 -13.664946 90)
			(size 0.3556 1.2192)
			(layers "F.Cu" "F.Mask" "F.Paste")
			(net "RST_SMB_NIC5_MUX_ISO_R_N")
		)
		(pad "A10" smd rect
			(at 3.322574 -13.064998 90)
			(size 0.3556 1.2192)
			(layers "F.Cu" "F.Mask" "F.Paste")
			(net "GND")
		)
		(pad "A11" smd rect
			(at 3.322574 -12.46505 90)
			(size 0.3556 1.2192)
			(layers "F.Cu" "F.Mask" "F.Paste")
			(net "RST_NIC5_PERST1_R_N")
		)
		(pad "A12" smd rect
			(at 3.322574 -11.865102 90)
			(size 0.3556 1.2192)
			(layers "F.Cu" "F.Mask" "F.Paste")
			(net "PRSNTB2_NIC5_N")
		)
		(pad "A13" smd rect
			(at 3.322574 -11.2649 90)
			(size 0.3556 1.2192)
			(layers "F.Cu" "F.Mask" "F.Paste")
			(net "GND")
		)
		(pad "A14" smd rect
			(at 3.322574 -10.664952 90)
			(size 0.3556 1.2192)
			(layers "F.Cu" "F.Mask" "F.Paste")
			(net "Net_2640")
		)
		(pad "A15" smd rect
			(at 3.322574 -10.065004 90)
			(size 0.3556 1.2192)
			(layers "F.Cu" "F.Mask" "F.Paste")
			(net "Net_2643")
		)
		(pad "A16" smd rect
			(at 3.322574 -9.465056 90)
			(size 0.3556 1.2192)
			(layers "F.Cu" "F.Mask" "F.Paste")
			(net "GND")
		)
		(pad "A17" smd rect
			(at 3.322574 -8.865108 90)
			(size 0.3556 1.2192)
			(layers "F.Cu" "F.Mask" "F.Paste")
			(net "P5E_PEX2_STN0_RX_DN<0>")
		)
		(pad "A18" smd rect
			(at 3.322574 -8.264906 90)
			(size 0.3556 1.2192)
			(layers "F.Cu" "F.Mask" "F.Paste")
			(net "P5E_PEX2_STN0_RX_DP<0>")
		)
		(pad "A19" smd rect
			(at 3.322574 -7.664958 90)
			(size 0.3556 1.2192)
			(layers "F.Cu" "F.Mask" "F.Paste")
			(net "GND")
		)
		(pad "A20" smd rect
			(at 3.322574 -7.06501 90)
			(size 0.3556 1.2192)
			(layers "F.Cu" "F.Mask" "F.Paste")
			(net "P5E_PEX2_STN0_RX_DN<1>")
		)
		(pad "A21" smd rect
			(at 3.322574 -6.465062 90)
			(size 0.3556 1.2192)
			(layers "F.Cu" "F.Mask" "F.Paste")
			(net "P5E_PEX2_STN0_RX_DP<1>")
		)
		(pad "A22" smd rect
			(at 3.322574 -5.865114 90)
			(size 0.3556 1.2192)
			(layers "F.Cu" "F.Mask" "F.Paste")
			(net "GND")
		)
		(pad "A23" smd rect
			(at 3.322574 -5.264912 90)
			(size 0.3556 1.2192)
			(layers "F.Cu" "F.Mask" "F.Paste")
			(net "P5E_PEX2_STN0_RX_DN<2>")
		)
		(pad "A24" smd rect
			(at 3.322574 -4.664964 90)
			(size 0.3556 1.2192)
			(layers "F.Cu" "F.Mask" "F.Paste")
			(net "P5E_PEX2_STN0_RX_DP<2>")
		)
		(pad "A25" smd rect
			(at 3.322574 -4.065016 90)
			(size 0.3556 1.2192)
			(layers "F.Cu" "F.Mask" "F.Paste")
			(net "GND")
		)
		(pad "A26" smd rect
			(at 3.322574 -3.465068 90)
			(size 0.3556 1.2192)
			(layers "F.Cu" "F.Mask" "F.Paste")
			(net "P5E_PEX2_STN0_RX_DN<3>")
		)
		(pad "A27" smd rect
			(at 3.322574 -2.86512 90)
			(size 0.3556 1.2192)
			(layers "F.Cu" "F.Mask" "F.Paste")
			(net "P5E_PEX2_STN0_RX_DP<3>")
		)
		(pad "A28" smd rect
			(at 3.322574 -2.264918 90)
			(size 0.3556 1.2192)
			(layers "F.Cu" "F.Mask" "F.Paste")
			(net "GND")
		)
		(pad "A29" smd rect
			(at 3.322574 1.74498 90)
			(size 0.3556 1.2192)
			(layers "F.Cu" "F.Mask" "F.Paste")
			(net "GND")
		)
		(pad "A30" smd rect
			(at 3.322574 2.344928 90)
			(size 0.3556 1.2192)
			(layers "F.Cu" "F.Mask" "F.Paste")
			(net "P5E_PEX2_STN0_RX_DN<4>")
		)
		(pad "A31" smd rect
			(at 3.322574 2.944876 90)
			(size 0.3556 1.2192)
			(layers "F.Cu" "F.Mask" "F.Paste")
			(net "P5E_PEX2_STN0_RX_DP<4>")
		)
		(pad "A32" smd rect
			(at 3.322574 3.545078 90)
			(size 0.3556 1.2192)
			(layers "F.Cu" "F.Mask" "F.Paste")
			(net "GND")
		)
		(pad "A33" smd rect
			(at 3.322574 4.145026 90)
			(size 0.3556 1.2192)
			(layers "F.Cu" "F.Mask" "F.Paste")
			(net "P5E_PEX2_STN0_RX_DN<5>")
		)
		(pad "A34" smd rect
			(at 3.322574 4.744974 90)
			(size 0.3556 1.2192)
			(layers "F.Cu" "F.Mask" "F.Paste")
			(net "P5E_PEX2_STN0_RX_DP<5>")
		)
		(pad "A35" smd rect
			(at 3.322574 5.344922 90)
			(size 0.3556 1.2192)
			(layers "F.Cu" "F.Mask" "F.Paste")
			(net "GND")
		)
		(pad "A36" smd rect
			(at 3.322574 5.945124 90)
			(size 0.3556 1.2192)
			(layers "F.Cu" "F.Mask" "F.Paste")
			(net "P5E_PEX2_STN0_RX_DN<6>")
		)
		(pad "A37" smd rect
			(at 3.322574 6.545072 90)
			(size 0.3556 1.2192)
			(layers "F.Cu" "F.Mask" "F.Paste")
			(net "P5E_PEX2_STN0_RX_DP<6>")
		)
		(pad "A38" smd rect
			(at 3.322574 7.14502 90)
			(size 0.3556 1.2192)
			(layers "F.Cu" "F.Mask" "F.Paste")
			(net "GND")
		)
		(pad "A39" smd rect
			(at 3.322574 7.744968 90)
			(size 0.3556 1.2192)
			(layers "F.Cu" "F.Mask" "F.Paste")
			(net "P5E_PEX2_STN0_RX_DN<7>")
		)
		(pad "A40" smd rect
			(at 3.322574 8.344916 90)
			(size 0.3556 1.2192)
			(layers "F.Cu" "F.Mask" "F.Paste")
			(net "P5E_PEX2_STN0_RX_DP<7>")
		)
		(pad "A41" smd rect
			(at 3.322574 8.945118 90)
			(size 0.3556 1.2192)
			(layers "F.Cu" "F.Mask" "F.Paste")
			(net "GND")
		)
		(pad "A42" smd rect
			(at 3.322574 9.545066 90)
			(size 0.3556 1.2192)
			(layers "F.Cu" "F.Mask" "F.Paste")
			(net "PRSNTB1_NIC5_N")
		)
		(pad "A43" smd rect
			(at 3.322574 14.454886 90)
			(size 0.3556 1.2192)
			(layers "F.Cu" "F.Mask" "F.Paste")
			(net "GND")
		)
		(pad "A44" smd rect
			(at 3.322574 15.055088 90)
			(size 0.3556 1.2192)
			(layers "F.Cu" "F.Mask" "F.Paste")
			(net "P5E_PEX2_STN0_RX_DN<8>")
		)
		(pad "A45" smd rect
			(at 3.322574 15.655036 90)
			(size 0.3556 1.2192)
			(layers "F.Cu" "F.Mask" "F.Paste")
			(net "P5E_PEX2_STN0_RX_DP<8>")
		)
		(pad "A46" smd rect
			(at 3.322574 16.254984 90)
			(size 0.3556 1.2192)
			(layers "F.Cu" "F.Mask" "F.Paste")
			(net "GND")
		)
		(pad "A47" smd rect
			(at 3.322574 16.854932 90)
			(size 0.3556 1.2192)
			(layers "F.Cu" "F.Mask" "F.Paste")
			(net "P5E_PEX2_STN0_RX_DN<9>")
		)
		(pad "A48" smd rect
			(at 3.322574 17.45488 90)
			(size 0.3556 1.2192)
			(layers "F.Cu" "F.Mask" "F.Paste")
			(net "P5E_PEX2_STN0_RX_DP<9>")
		)
		(pad "A49" smd rect
			(at 3.322574 18.055082 90)
			(size 0.3556 1.2192)
			(layers "F.Cu" "F.Mask" "F.Paste")
			(net "GND")
		)
		(pad "A50" smd rect
			(at 3.322574 18.65503 90)
			(size 0.3556 1.2192)
			(layers "F.Cu" "F.Mask" "F.Paste")
			(net "P5E_PEX2_STN0_RX_DN<10>")
		)
		(pad "A51" smd rect
			(at 3.322574 19.254978 90)
			(size 0.3556 1.2192)
			(layers "F.Cu" "F.Mask" "F.Paste")
			(net "P5E_PEX2_STN0_RX_DP<10>")
		)
		(pad "A52" smd rect
			(at 3.322574 19.854926 90)
			(size 0.3556 1.2192)
			(layers "F.Cu" "F.Mask" "F.Paste")
			(net "GND")
		)
		(pad "A53" smd rect
			(at 3.322574 20.455128 90)
			(size 0.3556 1.2192)
			(layers "F.Cu" "F.Mask" "F.Paste")
			(net "P5E_PEX2_STN0_RX_DN<11>")
		)
		(pad "A54" smd rect
			(at 3.322574 21.055076 90)
			(size 0.3556 1.2192)
			(layers "F.Cu" "F.Mask" "F.Paste")
			(net "P5E_PEX2_STN0_RX_DP<11>")
		)
		(pad "A55" smd rect
			(at 3.322574 21.655024 90)
			(size 0.3556 1.2192)
			(layers "F.Cu" "F.Mask" "F.Paste")
			(net "GND")
		)
		(pad "A56" smd rect
			(at 3.322574 22.254972 90)
			(size 0.3556 1.2192)
			(layers "F.Cu" "F.Mask" "F.Paste")
			(net "P5E_PEX2_STN0_RX_DN<12>")
		)
		(pad "A57" smd rect
			(at 3.322574 22.85492 90)
			(size 0.3556 1.2192)
			(layers "F.Cu" "F.Mask" "F.Paste")
			(net "P5E_PEX2_STN0_RX_DP<12>")
		)
		(pad "A58" smd rect
			(at 3.322574 23.455122 90)
			(size 0.3556 1.2192)
			(layers "F.Cu" "F.Mask" "F.Paste")
			(net "GND")
		)
		(pad "A59" smd rect
			(at 3.322574 24.05507 90)
			(size 0.3556 1.2192)
			(layers "F.Cu" "F.Mask" "F.Paste")
			(net "P5E_PEX2_STN0_RX_DN<13>")
		)
		(pad "A60" smd rect
			(at 3.322574 24.655018 90)
			(size 0.3556 1.2192)
			(layers "F.Cu" "F.Mask" "F.Paste")
			(net "P5E_PEX2_STN0_RX_DP<13>")
		)
		(pad "A61" smd rect
			(at 3.322574 25.254966 90)
			(size 0.3556 1.2192)
			(layers "F.Cu" "F.Mask" "F.Paste")
			(net "GND")
		)
		(pad "A62" smd rect
			(at 3.322574 25.854914 90)
			(size 0.3556 1.2192)
			(layers "F.Cu" "F.Mask" "F.Paste")
			(net "P5E_PEX2_STN0_RX_DN<14>")
		)
		(pad "A63" smd rect
			(at 3.322574 26.455116 90)
			(size 0.3556 1.2192)
			(layers "F.Cu" "F.Mask" "F.Paste")
			(net "P5E_PEX2_STN0_RX_DP<14>")
		)
		(pad "A64" smd rect
			(at 3.322574 27.055064 90)
			(size 0.3556 1.2192)
			(layers "F.Cu" "F.Mask" "F.Paste")
			(net "GND")
		)
		(pad "A65" smd rect
			(at 3.322574 27.655012 90)
			(size 0.3556 1.2192)
			(layers "F.Cu" "F.Mask" "F.Paste")
			(net "P5E_PEX2_STN0_RX_DN<15>")
		)
		(pad "A66" smd rect
			(at 3.322574 28.25496 90)
			(size 0.3556 1.2192)
			(layers "F.Cu" "F.Mask" "F.Paste")
			(net "P5E_PEX2_STN0_RX_DP<15>")
		)
		(pad "A67" smd rect
			(at 3.322574 28.854908 90)
			(size 0.3556 1.2192)
			(layers "F.Cu" "F.Mask" "F.Paste")
			(net "GND")
		)
		(pad "A68" smd rect
			(at 3.322574 29.45511 90)
			(size 0.3556 1.2192)
			(layers "F.Cu" "F.Mask" "F.Paste")
			(net "Net_2648")
		)
		(pad "A69" smd rect
			(at 3.322574 30.055058 90)
			(size 0.3556 1.2192)
			(layers "F.Cu" "F.Mask" "F.Paste")
			(net "Net_2649")
		)
		(pad "A70" smd rect
			(at 3.322574 30.655006 90)
			(size 0.3556 1.2192)
			(layers "F.Cu" "F.Mask" "F.Paste")
			(net "NIC5_PWRBRK_R_N")
		)
		(pad "B1" smd rect
			(at -1.27762 -18.465038 90)
			(size 0.3556 1.2192)
			(layers "F.Cu" "F.Mask" "F.Paste")
			(net "P12V_NIC5")
		)
		(pad "B2" smd rect
			(at -1.27762 -17.86509 90)
			(size 0.3556 1.2192)
			(layers "F.Cu" "F.Mask" "F.Paste")
			(net "P12V_NIC5")
		)
		(pad "B3" smd rect
			(at -1.27762 -17.264888 90)
			(size 0.3556 1.2192)
			(layers "F.Cu" "F.Mask" "F.Paste")
			(net "P12V_NIC5")
		)
		(pad "B4" smd rect
			(at -1.27762 -16.66494 90)
			(size 0.3556 1.2192)
			(layers "F.Cu" "F.Mask" "F.Paste")
			(net "P12V_NIC5")
		)
		(pad "B5" smd rect
			(at -1.27762 -16.064992 90)
			(size 0.3556 1.2192)
			(layers "F.Cu" "F.Mask" "F.Paste")
			(net "P12V_NIC5")
		)
		(pad "B6" smd rect
			(at -1.27762 -15.465044 90)
			(size 0.3556 1.2192)
			(layers "F.Cu" "F.Mask" "F.Paste")
			(net "P12V_NIC5")
		)
		(pad "B7" smd rect
			(at -1.27762 -14.865096 90)
			(size 0.3556 1.2192)
			(layers "F.Cu" "F.Mask" "F.Paste")
			(net "NIC5_BIF0_N")
		)
		(pad "B8" smd rect
			(at -1.27762 -14.264894 90)
			(size 0.3556 1.2192)
			(layers "F.Cu" "F.Mask" "F.Paste")
			(net "NIC5_BIF1_N")
		)
		(pad "B9" smd rect
			(at -1.27762 -13.664946 90)
			(size 0.3556 1.2192)
			(layers "F.Cu" "F.Mask" "F.Paste")
			(net "NIC5_BIF2_N")
		)
		(pad "B10" smd rect
			(at -1.27762 -13.064998 90)
			(size 0.3556 1.2192)
			(layers "F.Cu" "F.Mask" "F.Paste")
			(net "RST_NIC5_PERST0_R_N")
		)
		(pad "B11" smd rect
			(at -1.27762 -12.46505 90)
			(size 0.3556 1.2192)
			(layers "F.Cu" "F.Mask" "F.Paste")
			(net "P3V3_NIC5")
		)
		(pad "B12" smd rect
			(at -1.27762 -11.865102 90)
			(size 0.3556 1.2192)
			(layers "F.Cu" "F.Mask" "F.Paste")
			(net "NIC5_AUX_PWR_EN_R")
		)
		(pad "B13" smd rect
			(at -1.27762 -11.2649 90)
			(size 0.3556 1.2192)
			(layers "F.Cu" "F.Mask" "F.Paste")
			(net "GND")
		)
		(pad "B14" smd rect
			(at -1.27762 -10.664952 90)
			(size 0.3556 1.2192)
			(layers "F.Cu" "F.Mask" "F.Paste")
			(net "CLK_100M_DB2000QL_NIC5_R_DN")
		)
		(pad "B15" smd rect
			(at -1.27762 -10.065004 90)
			(size 0.3556 1.2192)
			(layers "F.Cu" "F.Mask" "F.Paste")
			(net "CLK_100M_DB2000QL_NIC5_R_DP")
		)
		(pad "B16" smd rect
			(at -1.27762 -9.465056 90)
			(size 0.3556 1.2192)
			(layers "F.Cu" "F.Mask" "F.Paste")
			(net "GND")
		)
		(pad "B17" smd rect
			(at -1.27762 -8.865108 90)
			(size 0.3556 1.2192)
			(layers "F.Cu" "F.Mask" "F.Paste")
			(net "P5E_PEX2_STN0_TX_C_DN<0>")
		)
		(pad "B18" smd rect
			(at -1.27762 -8.264906 90)
			(size 0.3556 1.2192)
			(layers "F.Cu" "F.Mask" "F.Paste")
			(net "P5E_PEX2_STN0_TX_C_DP<0>")
		)
		(pad "B19" smd rect
			(at -1.27762 -7.664958 90)
			(size 0.3556 1.2192)
			(layers "F.Cu" "F.Mask" "F.Paste")
			(net "GND")
		)
		(pad "B20" smd rect
			(at -1.27762 -7.06501 90)
			(size 0.3556 1.2192)
			(layers "F.Cu" "F.Mask" "F.Paste")
			(net "P5E_PEX2_STN0_TX_C_DN<1>")
		)
		(pad "B21" smd rect
			(at -1.27762 -6.465062 90)
			(size 0.3556 1.2192)
			(layers "F.Cu" "F.Mask" "F.Paste")
			(net "P5E_PEX2_STN0_TX_C_DP<1>")
		)
		(pad "B22" smd rect
			(at -1.27762 -5.865114 90)
			(size 0.3556 1.2192)
			(layers "F.Cu" "F.Mask" "F.Paste")
			(net "GND")
		)
		(pad "B23" smd rect
			(at -1.27762 -5.264912 90)
			(size 0.3556 1.2192)
			(layers "F.Cu" "F.Mask" "F.Paste")
			(net "P5E_PEX2_STN0_TX_C_DN<2>")
		)
		(pad "B24" smd rect
			(at -1.27762 -4.664964 90)
			(size 0.3556 1.2192)
			(layers "F.Cu" "F.Mask" "F.Paste")
			(net "P5E_PEX2_STN0_TX_C_DP<2>")
		)
		(pad "B25" smd rect
			(at -1.27762 -4.065016 90)
			(size 0.3556 1.2192)
			(layers "F.Cu" "F.Mask" "F.Paste")
			(net "GND")
		)
		(pad "B26" smd rect
			(at -1.27762 -3.465068 90)
			(size 0.3556 1.2192)
			(layers "F.Cu" "F.Mask" "F.Paste")
			(net "P5E_PEX2_STN0_TX_C_DN<3>")
		)
		(pad "B27" smd rect
			(at -1.27762 -2.86512 90)
			(size 0.3556 1.2192)
			(layers "F.Cu" "F.Mask" "F.Paste")
			(net "P5E_PEX2_STN0_TX_C_DP<3>")
		)
		(pad "B28" smd rect
			(at -1.27762 -2.264918 90)
			(size 0.3556 1.2192)
			(layers "F.Cu" "F.Mask" "F.Paste")
			(net "GND")
		)
		(pad "B29" smd rect
			(at -1.27762 1.74498 90)
			(size 0.3556 1.2192)
			(layers "F.Cu" "F.Mask" "F.Paste")
			(net "GND")
		)
		(pad "B30" smd rect
			(at -1.27762 2.344928 90)
			(size 0.3556 1.2192)
			(layers "F.Cu" "F.Mask" "F.Paste")
			(net "P5E_PEX2_STN0_TX_C_DN<4>")
		)
		(pad "B31" smd rect
			(at -1.27762 2.944876 90)
			(size 0.3556 1.2192)
			(layers "F.Cu" "F.Mask" "F.Paste")
			(net "P5E_PEX2_STN0_TX_C_DP<4>")
		)
		(pad "B32" smd rect
			(at -1.27762 3.545078 90)
			(size 0.3556 1.2192)
			(layers "F.Cu" "F.Mask" "F.Paste")
			(net "GND")
		)
		(pad "B33" smd rect
			(at -1.27762 4.145026 90)
			(size 0.3556 1.2192)
			(layers "F.Cu" "F.Mask" "F.Paste")
			(net "P5E_PEX2_STN0_TX_C_DN<5>")
		)
		(pad "B34" smd rect
			(at -1.27762 4.744974 90)
			(size 0.3556 1.2192)
			(layers "F.Cu" "F.Mask" "F.Paste")
			(net "P5E_PEX2_STN0_TX_C_DP<5>")
		)
		(pad "B35" smd rect
			(at -1.27762 5.344922 90)
			(size 0.3556 1.2192)
			(layers "F.Cu" "F.Mask" "F.Paste")
			(net "GND")
		)
		(pad "B36" smd rect
			(at -1.27762 5.945124 90)
			(size 0.3556 1.2192)
			(layers "F.Cu" "F.Mask" "F.Paste")
			(net "P5E_PEX2_STN0_TX_C_DN<6>")
		)
		(pad "B37" smd rect
			(at -1.27762 6.545072 90)
			(size 0.3556 1.2192)
			(layers "F.Cu" "F.Mask" "F.Paste")
			(net "P5E_PEX2_STN0_TX_C_DP<6>")
		)
	)
)
